(kicad_pcb
	(version 20260206)
	(generator "pcbnew")
	(generator_version "10.0")
	(general
		(thickness 1.6)
		(legacy_teardrops no)
	)
	(paper "A4")
	(title_block
		(title "Bryce Canyon_R.DPB_16317-1_OCP.brd")
		(comment 1 "Bryce Canyon / footprints 1081-1083 of 2099")
	)
	(layers
		(0 "F.Cu" signal "TOP")
		(4 "In1.Cu" signal "L2GND")
		(6 "In2.Cu" signal "L3")
		(8 "In3.Cu" signal "L4VCC")
		(10 "In4.Cu" signal "L5VCC")
		(12 "In5.Cu" signal "L6")
		(14 "In6.Cu" signal "L7GND")
		(2 "B.Cu" signal "BOTTOM")
		(9 "F.Adhes" user "F.Adhesive")
		(11 "B.Adhes" user "B.Adhesive")
		(13 "F.Paste" user "Package Geometry/Pastemask Top")
		(15 "B.Paste" user "Package Geometry/Pastemask Bottom")
		(5 "F.SilkS" user "Ref Des/Silkscreen Top")
		(7 "B.SilkS" user "Ref Des/Silkscreen Bottom")
		(1 "F.Mask" user "Board Geometry/Soldermask Top")
		(3 "B.Mask" user "Board Geometry/Soldermask Bottom")
		(17 "Dwgs.User" user "User.Drawings")
		(19 "Cmts.User" user "User.Comments")
		(21 "Eco1.User" user "User.Eco1")
		(23 "Eco2.User" user "User.Eco2")
		(25 "Edge.Cuts" user "Board Geometry/Outline")
		(27 "Margin" user)
		(31 "F.CrtYd" user "Package Geometry/Place Bound Top")
		(29 "B.CrtYd" user "Package Geometry/Place Bound Bottom")
		(35 "F.Fab" user "Ref Des/Assembly Top")
		(33 "B.Fab" user "Ref Des/Assembly Bottom")
	)
	(footprint ""
		(layer "F.Cu")
		(at 439.121804 -360.8324)
		(property "Reference" "Q133"
			(at 0 0 0)
			(layer "F.SilkS")
			(hide yes)
			(effects
				(font
					(size 1.27 1.27)
				)
			)
		)
		(property "Value" "AO4407AL-GP"
			(at -3.707384 -1.5367 0)
			(unlocked yes)
			(layer "F.Fab")
			(hide yes)
			(effects
				(font
					(size 1.016 1.016)
					(thickness 0.1524)
				)
			)
		)
		(property "Device Type" "SOIC8H69"
			(at -3.707384 -3.0607 0)
			(unlocked yes)
			(layer "F.Fab")
			(hide yes)
			(effects
				(font
					(size 1.016 1.016)
					(thickness 0.1524)
				)
			)
		)
		(duplicate_pad_numbers_are_jumpers no)
		(fp_line
			(start -2.7432 -1.4224)
			(end -2.7432 1.4224)
			(stroke
				(width 0.1524)
				(type default)
			)
			(layer "F.SilkS")
		)
		(fp_line
			(start -2.7432 1.4224)
			(end -2.6416 1.4224)
			(stroke
				(width 0.1524)
				(type default)
			)
			(layer "F.SilkS")
		)
		(fp_line
			(start -2.7432 1.4224)
			(end 2.1336 1.4224)
			(stroke
				(width 0.1524)
				(type default)
			)
			(layer "F.SilkS")
		)
		(fp_line
			(start -2.7178 -0.508)
			(end -2.1844 -0.0508)
			(stroke
				(width 0.1524)
				(type default)
			)
			(layer "F.SilkS")
		)
		(fp_line
			(start -2.6289 3.4417)
			(end -2.6289 1.4732)
			(stroke
				(width 0.381)
				(type default)
			)
			(layer "F.SilkS")
		)
		(fp_line
			(start -2.1844 -0.0508)
			(end -2.7178 0.508)
			(stroke
				(width 0.1524)
				(type default)
			)
			(layer "F.SilkS")
		)
		(fp_line
			(start 2.1336 -1.4224)
			(end -2.7432 -1.4224)
			(stroke
				(width 0.1524)
				(type default)
			)
			(layer "F.SilkS")
		)
		(fp_line
			(start 2.1336 1.4224)
			(end 2.1336 -1.4224)
			(stroke
				(width 0.1524)
				(type default)
			)
			(layer "F.SilkS")
		)
		(fp_poly
			(pts
				(xy -2.2098 -1.4224) (xy -2.2098 1.4224) (xy 2.2098 1.4224) (xy 2.2098 -1.4224)
			)
			(stroke
				(width 0)
				(type default)
			)
			(fill yes)
			(layer "F.SilkS")
		)
		(fp_rect
			(start -2.450084 2.999994)
			(end 2.450084 -2.999994)
			(stroke
				(width 0)
				(type default)
			)
			(fill no)
			(layer "F.CrtYd")
		)
		(fp_poly
			(pts
				(xy -2.8194 3.6322) (xy -2.8194 -3.6322) (xy 2.8194 -3.6322) (xy 2.8194 1.18364) (xy 2.450084 1.18364)
				(xy 2.450084 -2.999994) (xy -2.450084 -2.999994) (xy -2.450084 2.999994) (xy 2.450084 2.999994)
				(xy 2.450084 1.18618) (xy 2.8194 1.18618) (xy 2.8194 3.6322)
			)
			(stroke
				(width 0)
				(type default)
			)
			(fill no)
			(layer "F.CrtYd")
		)
		(fp_rect
			(start -2.8194 3.6322)
			(end 2.8194 -3.6322)
			(stroke
				(width 0)
				(type default)
			)
			(fill no)
			(layer "F.Fab")
		)
		(pad "1" smd rect
			(at -1.905 2.54)
			(size 0.635 1.651)
			(layers "F.Cu" "F.Mask" "F.Paste")
			(net "P12V_IN")
		)
		(pad "2" smd rect
			(at -0.635 2.54)
			(size 0.635 1.651)
			(layers "F.Cu" "F.Mask" "F.Paste")
			(net "P12V_IN")
		)
		(pad "3" smd rect
			(at 0.635 2.54)
			(size 0.635 1.651)
			(layers "F.Cu" "F.Mask" "F.Paste")
			(net "P12V_IN")
		)
		(pad "4" smd rect
			(at 1.905 2.54)
			(size 0.635 1.651)
			(layers "F.Cu" "F.Mask" "F.Paste")
			(net "GATE_FAN3_R")
		)
		(pad "5" smd rect
			(at 1.905 -2.54)
			(size 0.635 1.651)
			(layers "F.Cu" "F.Mask" "F.Paste")
			(net "P12V_FAN3")
		)
		(pad "6" smd rect
			(at 0.635 -2.54)
			(size 0.635 1.651)
			(layers "F.Cu" "F.Mask" "F.Paste")
			(net "P12V_FAN3")
		)
		(pad "7" smd rect
			(at -0.635 -2.54)
			(size 0.635 1.651)
			(layers "F.Cu" "F.Mask" "F.Paste")
			(net "P12V_FAN3")
		)
		(pad "8" smd rect
			(at -1.905 -2.54)
			(size 0.635 1.651)
			(layers "F.Cu" "F.Mask" "F.Paste")
			(net "P12V_FAN3")
		)
	)
	(footprint ""
		(layer "F.Cu")
		(at 483.300024 -143.91005 -90)
		(property "Reference" "HDDSAS23"
			(at 0 0 270)
			(layer "F.SilkS")
			(hide yes)
			(effects
				(font
					(size 1.27 1.27)
				)
			)
		)
		(property "Value" "SKT-SAS15P-14P-45-GP"
			(at -20.7645 -8.9789 270)
			(unlocked yes)
			(layer "F.Fab")
			(hide yes)
			(effects
				(font
					(size 1.016 1.016)
					(thickness 0.1524)
				)
			)
		)
		(property "Device Type" "10120818-001C-TRLF"
			(at -20.7645 -10.5029 270)
			(unlocked yes)
			(layer "F.Fab")
			(hide yes)
			(effects
				(font
					(size 1.016 1.016)
					(thickness 0.1524)
				)
			)
		)
		(duplicate_pad_numbers_are_jumpers no)
		(fp_line
			(start 1.651 4.2926)
			(end 1.651 3.0099)
			(stroke
				(width 0.1524)
				(type default)
			)
			(layer "F.SilkS")
		)
		(fp_line
			(start 8.509 4.2926)
			(end 1.651 4.2926)
			(stroke
				(width 0.1524)
				(type default)
			)
			(layer "F.SilkS")
		)
		(fp_line
			(start -23.4188 3.0099)
			(end -23.4188 -3.2512)
			(stroke
				(width 0.1524)
				(type default)
			)
			(layer "F.SilkS")
		)
		(fp_line
			(start 1.651 3.0099)
			(end -23.4188 3.0099)
			(stroke
				(width 0.1524)
				(type default)
			)
			(layer "F.SilkS")
		)
		(fp_line
			(start 8.509 3.0099)
			(end 8.509 4.2926)
			(stroke
				(width 0.1524)
				(type default)
			)
			(layer "F.SilkS")
		)
		(fp_line
			(start 23.4188 3.0099)
			(end 8.509 3.0099)
			(stroke
				(width 0.1524)
				(type default)
			)
			(layer "F.SilkS")
		)
		(fp_line
			(start -23.4188 -3.2512)
			(end 23.4188 -3.2512)
			(stroke
				(width 0.1524)
				(type default)
			)
			(layer "F.SilkS")
		)
		(fp_line
			(start 23.4188 -3.2512)
			(end 23.4188 3.0099)
			(stroke
				(width 0.1524)
				(type default)
			)
			(layer "F.SilkS")
		)
		(fp_line
			(start 15.5067 -3.3401)
			(end 16.2687 -3.3401)
			(stroke
				(width 0.3302)
				(type default)
			)
			(layer "F.SilkS")
		)
		(fp_poly
			(pts
				(xy 15.868904 -3.230372) (xy 16.503904 -3.865372) (xy 15.233904 -3.865372)
			)
			(stroke
				(width 0)
				(type default)
			)
			(fill yes)
			(layer "F.SilkS")
		)
		(fp_poly
			(pts
				(xy -22.8727 -2.7559) (xy 22.8727 -2.7559) (xy 22.8727 2.7559) (xy 8.255 2.7559) (xy 8.255 3.5179)
				(xy 1.905 3.5179) (xy 1.905 2.7559) (xy -22.8727 2.7559)
			)
			(stroke
				(width 0)
				(type default)
			)
			(fill no)
			(layer "F.CrtYd")
		)
		(fp_poly
			(pts
				(xy 1.397 4.5466) (xy 1.397 3.2639) (xy -23.6728 3.2639) (xy -23.6728 -3.5052) (xy 23.6728 -3.5052)
				(xy 23.6728 -0.00635) (xy 22.8727 -0.00635) (xy 22.8727 -2.7559) (xy -22.8727 -2.7559) (xy -22.8727 2.7559)
				(xy 1.905 2.7559) (xy 1.905 3.5179) (xy 8.255 3.5179) (xy 8.255 2.7559) (xy 22.8727 2.7559) (xy 22.8727 0.00635)
				(xy 23.6728 0.00635) (xy 23.6728 3.2639) (xy 8.763 3.2639) (xy 8.763 4.5466)
			)
			(stroke
				(width 0)
				(type default)
			)
			(fill no)
			(layer "F.CrtYd")
		)
		(fp_poly
			(pts
				(xy 1.397 4.5466) (xy 1.397 3.2639) (xy -23.6728 3.2639) (xy -23.6728 -3.5052) (xy 23.6728 -3.5052)
				(xy 23.6728 3.2639) (xy 8.763 3.2639) (xy 8.763 4.5466)
			)
			(stroke
				(width 0)
				(type default)
			)
			(fill no)
			(layer "F.Fab")
		)
		(pad "" np_thru_hole circle
			(at -18.874994 0 270)
			(size 0.254 0.254)
			(drill 1.3462)
			(layers "*.Cu" "*.Mask")
			(clearance 0.9017)
			(thermal_gap 0.9017)
		)
		(pad "" np_thru_hole circle
			(at 18.874994 0 270)
			(size 0.254 0.254)
			(drill 0.9398)
			(layers "*.Cu" "*.Mask")
			(clearance 0.6985)
			(thermal_gap 0.6985)
		)
		(pad "G1" smd rect
			(at 21.874988 0 270)
			(size 2.5908 2.5908)
			(layers "F.Cu" "F.Mask" "F.Paste")
			(net "GND")
		)
		(pad "G2" smd rect
			(at -21.874988 0 270)
			(size 2.5908 2.5908)
			(layers "F.Cu" "F.Mask" "F.Paste")
			(net "GND")
		)
		(pad "P1" smd rect
			(at 1.905 -1.82499 270)
			(size 0.6096 2.3622)
			(layers "F.Cu" "F.Mask" "F.Paste")
			(net "Net_1684")
		)
		(pad "P2" smd rect
			(at 0.635 -1.82499 270)
			(size 0.6096 2.3622)
			(layers "F.Cu" "F.Mask" "F.Paste")
			(net "Net_1685")
		)
		(pad "P3" smd rect
			(at -0.635 -1.82499 270)
			(size 0.6096 2.3622)
			(layers "F.Cu" "F.Mask" "F.Paste")
			(net "Net_1686")
		)
		(pad "P4" smd rect
			(at -1.905 -1.82499 270)
			(size 0.6096 2.3622)
			(layers "F.Cu" "F.Mask" "F.Paste")
			(net "GND")
		)
		(pad "P5" smd rect
			(at -3.175 -1.82499 270)
			(size 0.6096 2.3622)
			(layers "F.Cu" "F.Mask" "F.Paste")
			(net "HDD_PRSNT_23")
		)
		(pad "P6" smd rect
			(at -4.445 -1.82499 270)
			(size 0.6096 2.3622)
			(layers "F.Cu" "F.Mask" "F.Paste")
			(net "GND")
		)
		(pad "P7" smd rect
			(at -5.715 -1.82499 270)
			(size 0.6096 2.3622)
			(layers "F.Cu" "F.Mask" "F.Paste")
			(net "5V_PRE_23")
		)
		(pad "P8" smd rect
			(at -6.985 -1.82499 270)
			(size 0.6096 2.3622)
			(layers "F.Cu" "F.Mask" "F.Paste")
			(net "P5V_HDD23")
		)
		(pad "P9" smd rect
			(at -8.255 -1.82499 270)
			(size 0.6096 2.3622)
			(layers "F.Cu" "F.Mask" "F.Paste")
			(net "P5V_HDD23")
		)
		(pad "P10" smd rect
			(at -9.525 -1.82499 270)
			(size 0.6096 2.3622)
			(layers "F.Cu" "F.Mask" "F.Paste")
			(net "GND")
		)
		(pad "P11" smd rect
			(at -10.795 -1.82499 270)
			(size 0.6096 2.3622)
			(layers "F.Cu" "F.Mask" "F.Paste")
			(net "ACT_HDD_23")
		)
		(pad "P12" smd rect
			(at -12.065 -1.82499 270)
			(size 0.6096 2.3622)
			(layers "F.Cu" "F.Mask" "F.Paste")
			(net "GND")
		)
		(pad "P13" smd rect
			(at -13.335 -1.82499 270)
			(size 0.6096 2.3622)
			(layers "F.Cu" "F.Mask" "F.Paste")
			(net "12V_PRE_23")
		)
		(pad "P14" smd rect
			(at -14.605 -1.82499 270)
			(size 0.6096 2.3622)
			(layers "F.Cu" "F.Mask" "F.Paste")
			(net "P12V_HDD23")
		)
		(pad "P15" smd rect
			(at -15.875 -1.82499 270)
			(size 0.6096 2.3622)
			(layers "F.Cu" "F.Mask" "F.Paste")
			(net "P12V_HDD23")
		)
		(pad "S1" smd rect
			(at 15.875 -1.82499 270)
			(size 0.6096 2.3622)
			(layers "F.Cu" "F.Mask" "F.Paste")
			(net "GND")
		)
		(pad "S2" smd rect
			(at 14.605 -1.82499 270)
			(size 0.6096 2.3622)
			(layers "F.Cu" "F.Mask" "F.Paste")
			(net "SAS_HDD_RX_P23")
		)
		(pad "S3" smd rect
			(at 13.335 -1.82499 270)
			(size 0.6096 2.3622)
			(layers "F.Cu" "F.Mask" "F.Paste")
			(net "SAS_HDD_RX_N23")
		)
		(pad "S4" smd rect
			(at 12.065 -1.82499 270)
			(size 0.6096 2.3622)
			(layers "F.Cu" "F.Mask" "F.Paste")
			(net "GND")
		)
		(pad "S5" smd rect
			(at 10.795 -1.82499 270)
			(size 0.6096 2.3622)
			(layers "F.Cu" "F.Mask" "F.Paste")
			(net "PHY_DRV_B_TO_SCC_B_23_DN")
		)
		(pad "S6" smd rect
			(at 9.525 -1.82499 270)
			(size 0.6096 2.3622)
			(layers "F.Cu" "F.Mask" "F.Paste")
			(net "PHY_DRV_B_TO_SCC_B_23_DP")
		)
		(pad "S7" smd rect
			(at 8.255 -1.82499 270)
			(size 0.6096 2.3622)
			(layers "F.Cu" "F.Mask" "F.Paste")
			(net "GND")
		)
		(pad "S8" smd rect
			(at 7.480046 2.845054 270)
			(size 0.508 2.3622)
			(layers "F.Cu" "F.Mask" "F.Paste")
			(net "GND")
		)
		(pad "S9" smd rect
			(at 6.679946 2.845054 270)
			(size 0.508 2.3622)
			(layers "F.Cu" "F.Mask" "F.Paste")
			(net "Net_447")
		)
		(pad "S10" smd rect
			(at 5.8801 2.845054 270)
			(size 0.508 2.3622)
			(layers "F.Cu" "F.Mask" "F.Paste")
			(net "Net_339")
		)
		(pad "S11" smd rect
			(at 5.08 2.845054 270)
			(size 0.508 2.3622)
			(layers "F.Cu" "F.Mask" "F.Paste")
			(net "GND")
		)
		(pad "S12" smd rect
			(at 4.2799 2.845054 270)
			(size 0.508 2.3622)
			(layers "F.Cu" "F.Mask" "F.Paste")
			(net "Net_375")
		)
		(pad "S13" smd rect
			(at 3.480054 2.845054 270)
			(size 0.508 2.3622)
			(layers "F.Cu" "F.Mask" "F.Paste")
			(net "Net_411")
		)
		(pad "S14" smd rect
			(at 2.679954 2.845054 270)
			(size 0.508 2.3622)
			(layers "F.Cu" "F.Mask" "F.Paste")
			(net "GND")
		)
		(zone
			(layer "F.Cu")
			(hatch none 0.5)
			(connect_pads
				(clearance 0)
			)
			(min_thickness 0.25)
			(keepout
				(tracks not_allowed)
				(vias allowed)
				(pads allowed)
				(copperpour not_allowed)
				(footprints allowed)
			)
			(placement
				(enabled no)
				(sheetname "")
			)
			(fill
				(thermal_gap 0.5)
				(thermal_bridge_width 0.5)
				(island_removal_mode 0)
			)
			(polygon
				(pts
					(xy 486.957624 -160.64865) (xy 479.883724 -160.64865) (xy 479.883724 -167.58285) (xy 480.988624 -167.58285)
					(xy 480.988624 -163.46805) (xy 485.611424 -163.46805) (xy 485.611424 -167.58285) (xy 486.957624 -167.58285)
				)
			)
		)
		(zone
			(layer "F.Cu")
			(hatch none 0.5)
			(connect_pads
				(clearance 0)
			)
			(min_thickness 0.25)
			(keepout
				(tracks allowed)
				(vias not_allowed)
				(pads allowed)
				(copperpour not_allowed)
				(footprints allowed)
			)
			(placement
				(enabled no)
				(sheetname "")
			)
			(fill
				(thermal_gap 0.5)
				(thermal_bridge_width 0.5)
				(island_removal_mode 0)
			)
			(polygon
				(pts
					(xy 486.957624 -160.64865) (xy 479.883724 -160.64865) (xy 479.883724 -167.58285) (xy 480.988624 -167.58285)
					(xy 480.988624 -163.46805) (xy 485.611424 -163.46805) (xy 485.611424 -167.58285) (xy 486.957624 -167.58285)
				)
			)
		)
		(zone
			(layer "F.Cu")
			(hatch none 0.5)
			(connect_pads
				(clearance 0)
			)
			(min_thickness 0.25)
			(keepout
				(tracks allowed)
				(vias not_allowed)
				(pads allowed)
				(copperpour not_allowed)
				(footprints allowed)
			)
			(placement
				(enabled no)
				(sheetname "")
			)
			(fill
				(thermal_gap 0.5)
				(thermal_bridge_width 0.5)
				(island_removal_mode 0)
			)
			(polygon
				(pts
					(xy 486.957624 -127.17145) (xy 479.883724 -127.17145) (xy 479.883724 -120.23725) (xy 480.988624 -120.23725)
					(xy 480.988624 -124.35205) (xy 485.611424 -124.35205) (xy 485.611424 -120.23725) (xy 486.957624 -120.23725)
				)
			)
		)
		(zone
			(layer "F.Cu")
			(hatch none 0.5)
			(connect_pads
				(clearance 0)
			)
			(min_thickness 0.25)
			(keepout
				(tracks not_allowed)
				(vias allowed)
				(pads allowed)
				(copperpour not_allowed)
				(footprints allowed)
			)
			(placement
				(enabled no)
				(sheetname "")
			)
			(fill
				(thermal_gap 0.5)
				(thermal_bridge_width 0.5)
				(island_removal_mode 0)
			)
			(polygon
				(pts
					(xy 486.957624 -127.17145) (xy 479.883724 -127.17145) (xy 479.883724 -120.23725) (xy 480.988624 -120.23725)
					(xy 480.988624 -124.35205) (xy 485.611424 -124.35205) (xy 485.611424 -120.23725) (xy 486.957624 -120.23725)
				)
			)
		)
		(zone
			(layers "F.Cu" "B.Cu" "In1.Cu" "In2.Cu" "In3.Cu" "In4.Cu" "In5.Cu" "In6.Cu")
			(hatch none 0.5)
			(connect_pads
				(clearance 0)
			)
			(min_thickness 0.25)
			(keepout
				(tracks not_allowed)
				(vias allowed)
				(pads allowed)
				(copperpour not_allowed)
				(footprints allowed)
			)
			(placement
				(enabled no)
				(sheetname "")
			)
			(fill
				(thermal_gap 0.5)
				(thermal_bridge_width 0.5)
				(island_removal_mode 0)
			)
			(polygon
				(pts
					(arc
						(start 484.074724 -125.035056)
						(mid 482.525324 -125.035056)
						(end 484.074724 -125.035056)
					)
				)
			)
		)
		(zone
			(layers "F.Cu" "B.Cu" "In1.Cu" "In2.Cu" "In3.Cu" "In4.Cu" "In5.Cu" "In6.Cu")
			(hatch none 0.5)
			(connect_pads
				(clearance 0)
			)
			(min_thickness 0.25)
			(keepout
				(tracks not_allowed)
				(vias allowed)
				(pads allowed)
				(copperpour not_allowed)
				(footprints allowed)
			)
			(placement
				(enabled no)
				(sheetname "")
			)
			(fill
				(thermal_gap 0.5)
				(thermal_bridge_width 0.5)
				(island_removal_mode 0)
			)
			(polygon
				(pts
					(arc
						(start 484.277924 -162.785044)
						(mid 482.322124 -162.785044)
						(end 484.277924 -162.785044)
					)
				)
			)
		)
	)
	(footprint ""
		(layer "F.Cu")
		(at 248.524522 -366.623346 180)
		(property "Reference" "C570"
			(at 0 0 180)
			(layer "F.SilkS")
			(hide yes)
			(effects
				(font
					(size 1.27 1.27)
				)
			)
		)
		(property "Value" "SCD015U25V2KX-GP"
			(at 1.1811 -2.7051 180)
			(unlocked yes)
			(layer "F.Fab")
			(hide yes)
			(effects
				(font
					(size 1.016 1.016)
					(thickness 0.1524)
				)
			)
		)
		(property "Device Type" "C402H22"
			(at 1.1811 -4.2291 180)
			(unlocked yes)
			(layer "F.Fab")
			(hide yes)
			(effects
				(font
					(size 1.016 1.016)
					(thickness 0.1524)
				)
			)
		)
		(duplicate_pad_numbers_are_jumpers no)
		(fp_rect
			(start -0.4318 0.9525)
			(end 0.4318 -0.9525)
			(stroke
				(width 0)
				(type default)
			)
			(fill no)
			(layer "F.CrtYd")
		)
		(fp_rect
			(start -0.4318 0.9525)
			(end 0.4318 -0.9525)
			(stroke
				(width 0)
				(type default)
			)
			(fill no)
			(layer "F.Fab")
		)
		(pad "1" smd custom
			(at 0 -0.4445 180)
			(size 0.1524 0.1524)
			(layers "F.Cu" "F.Mask" "F.Paste")
			(net "MB3_HS_SENSE_P")
			(options
				(clearance outline)
				(anchor circle)
			)
			(primitives
				(gr_poly
					(pts
						(arc
							(start 0.3048 -0.2032)
							(mid 0.275042 -0.275042)
							(end 0.2032 -0.3048)
						)
						(arc
							(start -0.2032 -0.3048)
							(mid -0.275042 -0.275042)
							(end -0.3048 -0.2032)
						)
						(arc
							(start -0.3048 0.2032)
							(mid -0.275042 0.275042)
							(end -0.2032 0.3048)
						)
						(arc
							(start 0.2032 0.3048)
							(mid 0.275042 0.275042)
							(end 0.3048 0.2032)
						)
					)
					(width 0)
					(fill yes)
				)
			)
		)
		(pad "2" smd custom
			(at 0 0.4445 180)
			(size 0.1524 0.1524)
			(layers "F.Cu" "F.Mask" "F.Paste")
			(net "MB3_HS_SENSE_N")
			(options
				(clearance outline)
				(anchor circle)
			)
			(primitives
				(gr_poly
					(pts
						(arc
							(start 0.3048 -0.2032)
							(mid 0.275042 -0.275042)
							(end 0.2032 -0.3048)
						)
						(arc
							(start -0.2032 -0.3048)
							(mid -0.275042 -0.275042)
							(end -0.3048 -0.2032)
						)
						(arc
							(start -0.3048 0.2032)
							(mid -0.275042 0.275042)
							(end -0.2032 0.3048)
						)
						(arc
							(start 0.2032 0.3048)
							(mid 0.275042 0.275042)
							(end 0.3048 0.2032)
						)
					)
					(width 0)
					(fill yes)
				)
			)
		)
	)
)
